(kicad_pcb
	(version 20240108)
	(generator "pcbnew")
	(generator_version "8.0")
	(general
		(thickness 1.62)
		(legacy_teardrops no)
	)
	(paper "A4")
	(title_block
		(title "Jetson Orin Baseboard")
		(date "2025-03-12")
		(rev "1.3.4")
		(company "Antmicro Ltd")
		(comment 1 "www.antmicro.com")
		(comment 9 "footprints 408-411 of 677")
	)
	(layers
		(0 "F.Cu" signal)
		(1 "In1.Cu" signal)
		(2 "In2.Cu" signal)
		(3 "In3.Cu" signal)
		(4 "In4.Cu" jumper)
		(5 "In5.Cu" signal)
		(6 "In6.Cu" signal)
		(31 "B.Cu" signal)
		(32 "B.Adhes" user "B.Adhesive")
		(33 "F.Adhes" user "F.Adhesive")
		(34 "B.Paste" user)
		(35 "F.Paste" user)
		(36 "B.SilkS" user "B.Silkscreen")
		(37 "F.SilkS" user "F.Silkscreen")
		(38 "B.Mask" user)
		(39 "F.Mask" user)
		(40 "Dwgs.User" user "User.Drawings")
		(41 "Cmts.User" user "User.Comments")
		(42 "Eco1.User" user "User.Eco1")
		(43 "Eco2.User" user "User.Eco2")
		(44 "Edge.Cuts" user)
		(45 "Margin" user)
		(46 "B.CrtYd" user "B.Courtyard")
		(47 "F.CrtYd" user "F.Courtyard")
		(48 "B.Fab" user)
		(49 "F.Fab" user)
	)
	(footprint "antmicro-footprints:R_0402_1005Metric"
		(layer "B.Cu")
		(at 41.2 119.3 90)
		(descr "Resistor SMD 0402")
		(tags "resistor SMD 0402")
		(property "Reference" "R152"
			(at 3.68 0.4 -90)
			(layer "B.SilkS")
			(effects
				(font
					(size 0.7 0.7)
					(thickness 0.15)
				)
				(justify left bottom mirror)
			)
		)
		(property "Value" "R_200R_0402"
			(at 0 -1.4 -90)
			(layer "B.Fab")
			(effects
				(font
					(size 0.7 0.7)
					(thickness 0.15)
				)
				(justify left bottom mirror)
			)
		)
		(property "Footprint" "antmicro-footprints:R_0402_1005Metric"
			(at 0 0 90)
			(layer "F.Fab")
			(hide yes)
			(effects
				(font
					(size 1.27 1.27)
					(thickness 0.15)
				)
			)
		)
		(property "Datasheet" "https://www.bourns.com/docs/product-datasheets/cr.pdf"
			(at 0 0 90)
			(layer "F.Fab")
			(hide yes)
			(effects
				(font
					(size 1.27 1.27)
					(thickness 0.15)
				)
			)
		)
		(property "Author" "Antmicro"
			(at 160.5 78.1 0)
			(layer "B.Fab")
			(hide yes)
			(effects
				(font
					(size 1 1)
					(thickness 0.15)
				)
				(justify mirror)
			)
		)
		(property "License" "Apache-2.0"
			(at 160.5 78.1 0)
			(layer "B.Fab")
			(hide yes)
			(effects
				(font
					(size 1 1)
					(thickness 0.15)
				)
				(justify mirror)
			)
		)
		(property "MPN" "CR0402-FX-2000GLF"
			(at 160.5 78.1 0)
			(layer "B.Fab")
			(hide yes)
			(effects
				(font
					(size 1 1)
					(thickness 0.15)
				)
				(justify mirror)
			)
		)
		(property "Manufacturer" "Bourns"
			(at 160.5 78.1 0)
			(layer "B.Fab")
			(hide yes)
			(effects
				(font
					(size 1 1)
					(thickness 0.15)
				)
				(justify mirror)
			)
		)
		(property "Tolerance" "1%"
			(at 160.5 78.1 0)
			(layer "B.Fab")
			(hide yes)
			(effects
				(font
					(size 1 1)
					(thickness 0.15)
				)
				(justify mirror)
			)
		)
		(property "Val" "200R"
			(at 160.5 78.1 0)
			(layer "B.Fab")
			(hide yes)
			(effects
				(font
					(size 1 1)
					(thickness 0.15)
				)
				(justify mirror)
			)
		)
		(sheetname "Ethernet")
		(sheetfile "ethernet.kicad_sch")
		(attr smd)
		(fp_rect
			(start -0.925 0.47)
			(end 0.925 -0.47)
			(stroke
				(width 0.05)
				(type default)
			)
			(fill none)
			(layer "B.CrtYd")
		)
		(fp_rect
			(start -0.5 0.25)
			(end 0.5 -0.25)
			(stroke
				(width 0.15)
				(type solid)
			)
			(fill none)
			(layer "B.Fab")
		)
		(fp_text user "License: Apache-2.0"
			(at -0.95 -5.169 -90)
			(layer "B.Fab")
			(hide yes)
			(effects
				(font
					(size 0.7 0.7)
					(thickness 0.15)
				)
				(justify left bottom mirror)
			)
		)
		(fp_text user "${REFERENCE}"
			(at -0.95 -3.168 -90)
			(layer "B.Fab")
			(hide yes)
			(effects
				(font
					(size 0.7 0.7)
					(thickness 0.15)
				)
				(justify left bottom mirror)
			)
		)
		(fp_text user "Author: Antmicro"
			(at -0.95 -4.169 -90)
			(layer "B.Fab")
			(hide yes)
			(effects
				(font
					(size 0.7 0.7)
					(thickness 0.15)
				)
				(justify left bottom mirror)
			)
		)
		(pad "1" smd roundrect
			(at -0.48 0 90)
			(size 0.59 0.64)
			(layers "B.Cu" "B.Paste" "B.Mask")
			(roundrect_rratio 0.25)
			(net 551 "Net-(J6-LED_GRN-)")
			(pintype "passive")
		)
		(pad "2" smd roundrect
			(at 0.48 0 90)
			(size 0.59 0.64)
			(layers "B.Cu" "B.Paste" "B.Mask")
			(roundrect_rratio 0.25)
			(net 457 "GBE_LED_LINK")
			(pintype "passive")
		)
	)
	(footprint "antmicro-footprints:R_0402_1005Metric"
		(layer "B.Cu")
		(at 96.49 99.575 180)
		(descr "Resistor SMD 0402")
		(tags "resistor SMD 0402")
		(property "Reference" "R167"
			(at 1.63 1.575 -90)
			(layer "B.SilkS")
			(effects
				(font
					(size 0.7 0.7)
					(thickness 0.15)
				)
				(justify left bottom mirror)
			)
		)
		(property "Value" "R_0R_0402"
			(at 0 -1.4 0)
			(layer "B.Fab")
			(effects
				(font
					(size 0.7 0.7)
					(thickness 0.15)
				)
				(justify left bottom mirror)
			)
		)
		(property "Footprint" "antmicro-footprints:R_0402_1005Metric"
			(at 0 0 180)
			(layer "F.Fab")
			(hide yes)
			(effects
				(font
					(size 1.27 1.27)
					(thickness 0.15)
				)
			)
		)
		(property "Datasheet" "https://industrial.panasonic.com/cdbs/www-data/pdf/RDA0000/AOA0000C301.pdf"
			(at 0 0 180)
			(layer "F.Fab")
			(hide yes)
			(effects
				(font
					(size 1.27 1.27)
					(thickness 0.15)
				)
			)
		)
		(property "Author" "Antmicro"
			(at 192.98 199.15 0)
			(layer "B.Fab")
			(hide yes)
			(effects
				(font
					(size 1 1)
					(thickness 0.15)
				)
				(justify mirror)
			)
		)
		(property "Current" "1A"
			(at 192.98 199.15 0)
			(layer "B.Fab")
			(hide yes)
			(effects
				(font
					(size 1 1)
					(thickness 0.15)
				)
				(justify mirror)
			)
		)
		(property "License" "Apache-2.0"
			(at 192.98 199.15 0)
			(layer "B.Fab")
			(hide yes)
			(effects
				(font
					(size 1 1)
					(thickness 0.15)
				)
				(justify mirror)
			)
		)
		(property "MPN" "ERJ2GE0R00X"
			(at 192.98 199.15 0)
			(layer "B.Fab")
			(hide yes)
			(effects
				(font
					(size 1 1)
					(thickness 0.15)
				)
				(justify mirror)
			)
		)
		(property "Manufacturer" "Panasonic"
			(at 192.98 199.15 0)
			(layer "B.Fab")
			(hide yes)
			(effects
				(font
					(size 1 1)
					(thickness 0.15)
				)
				(justify mirror)
			)
		)
		(property "Tolerance" ""
			(at 192.98 199.15 0)
			(layer "B.Fab")
			(hide yes)
			(effects
				(font
					(size 1 1)
					(thickness 0.15)
				)
				(justify mirror)
			)
		)
		(property "Val" "0R"
			(at 192.98 199.15 0)
			(layer "B.Fab")
			(hide yes)
			(effects
				(font
					(size 1 1)
					(thickness 0.15)
				)
				(justify mirror)
			)
		)
		(sheetname "CSI")
		(sheetfile "csi.kicad_sch")
		(attr smd exclude_from_pos_files exclude_from_bom dnp)
		(fp_rect
			(start -0.925 0.47)
			(end 0.925 -0.47)
			(stroke
				(width 0.05)
				(type default)
			)
			(fill none)
			(layer "B.CrtYd")
		)
		(fp_rect
			(start -0.5 0.25)
			(end 0.5 -0.25)
			(stroke
				(width 0.15)
				(type solid)
			)
			(fill none)
			(layer "B.Fab")
		)
		(fp_text user "License: Apache-2.0"
			(at -0.95 -5.169 0)
			(layer "B.Fab")
			(hide yes)
			(effects
				(font
					(size 0.7 0.7)
					(thickness 0.15)
				)
				(justify left bottom mirror)
			)
		)
		(fp_text user "Author: Antmicro"
			(at -0.95 -4.169 0)
			(layer "B.Fab")
			(hide yes)
			(effects
				(font
					(size 0.7 0.7)
					(thickness 0.15)
				)
				(justify left bottom mirror)
			)
		)
		(fp_text user "${REFERENCE}"
			(at -0.95 -3.168 0)
			(layer "B.Fab")
			(hide yes)
			(effects
				(font
					(size 0.7 0.7)
					(thickness 0.15)
				)
				(justify left bottom mirror)
			)
		)
		(pad "1" smd roundrect
			(at -0.48 0 180)
			(size 0.59 0.64)
			(layers "B.Cu" "B.Paste" "B.Mask")
			(roundrect_rratio 0.25)
			(net 325 "/CSI/I2C_MUX_A0")
			(pintype "passive")
		)
		(pad "2" smd roundrect
			(at 0.48 0 180)
			(size 0.59 0.64)
			(layers "B.Cu" "B.Paste" "B.Mask")
			(roundrect_rratio 0.25)
			(net 112 "+1V8")
			(pintype "passive")
		)
	)
	(footprint "antmicro-footprints:R_Array_4x0201_Panasonic_EXB18V"
		(layer "B.Cu")
		(at 123.08 74.36 90)
		(property "Reference" "R103"
			(at -0.94 1.52 -90)
			(layer "B.SilkS")
			(effects
				(font
					(size 0.7 0.7)
					(thickness 0.15)
				)
				(justify right bottom mirror)
			)
		)
		(property "Value" "R_4x0R_0201_array"
			(at -1.1 -1.8 -90)
			(layer "B.Fab")
			(effects
				(font
					(size 0.7 0.7)
					(thickness 0.15)
				)
				(justify left bottom mirror)
			)
		)
		(property "Footprint" "antmicro-footprints:R_Array_4x0201_Panasonic_EXB18V"
			(at 0 0 90)
			(layer "F.Fab")
			(hide yes)
			(effects
				(font
					(size 1.27 1.27)
					(thickness 0.15)
				)
			)
		)
		(property "Datasheet" "http://industrial.panasonic.com/cdbs/www-data/pdf/AOC0000/AOC0000C14.pdf"
			(at 0 0 90)
			(layer "F.Fab")
			(hide yes)
			(effects
				(font
					(size 1.27 1.27)
					(thickness 0.15)
				)
			)
		)
		(property "Author" "Antmicro"
			(at 197.44 -48.72 0)
			(layer "B.Fab")
			(hide yes)
			(effects
				(font
					(size 1 1)
					(thickness 0.15)
				)
				(justify mirror)
			)
		)
		(property "License" "Apache-2.0"
			(at 197.44 -48.72 0)
			(layer "B.Fab")
			(hide yes)
			(effects
				(font
					(size 1 1)
					(thickness 0.15)
				)
				(justify mirror)
			)
		)
		(property "MPN" "EXB-18VR000X"
			(at 197.44 -48.72 0)
			(layer "B.Fab")
			(hide yes)
			(effects
				(font
					(size 1 1)
					(thickness 0.15)
				)
				(justify mirror)
			)
		)
		(property "Manufacturer" "Panasonic"
			(at 197.44 -48.72 0)
			(layer "B.Fab")
			(hide yes)
			(effects
				(font
					(size 1 1)
					(thickness 0.15)
				)
				(justify mirror)
			)
		)
		(property "Val" "4x0R_0201"
			(at 197.44 -48.72 0)
			(layer "B.Fab")
			(hide yes)
			(effects
				(font
					(size 1 1)
					(thickness 0.15)
				)
				(justify mirror)
			)
		)
		(sheetname "CSI")
		(sheetfile "csi.kicad_sch")
		(attr smd exclude_from_pos_files exclude_from_bom dnp)
		(fp_line
			(start 0.8 -0.45)
			(end 0.8 0.45)
			(stroke
				(width 0.12)
				(type solid)
			)
			(layer "B.SilkS")
		)
		(fp_line
			(start -0.8 -0.45)
			(end -0.8 0.45)
			(stroke
				(width 0.12)
				(type solid)
			)
			(layer "B.SilkS")
		)
		(fp_rect
			(start -0.898 0.66)
			(end 0.898 -0.65)
			(stroke
				(width 0.05)
				(type solid)
			)
			(fill none)
			(layer "B.CrtYd")
		)
		(fp_text user "License: Apache-2.0"
			(at -1.051 -6 -90)
			(layer "B.Fab")
			(hide yes)
			(effects
				(font
					(size 0.7 0.7)
					(thickness 0.15)
				)
				(justify left bottom mirror)
			)
		)
		(fp_text user "${REFERENCE}"
			(at -1.051 -3.2 -90)
			(layer "B.Fab")
			(hide yes)
			(effects
				(font
					(size 0.7 0.7)
					(thickness 0.15)
				)
				(justify left bottom mirror)
			)
		)
		(fp_text user "Author: Antmicro"
			(at -1.051 -4.599 -90)
			(layer "B.Fab")
			(hide yes)
			(effects
				(font
					(size 0.7 0.7)
					(thickness 0.15)
				)
				(justify left bottom mirror)
			)
		)
		(pad "1" smd roundrect
			(at -0.6 -0.298 90)
			(size 0.2 0.4)
			(layers "B.Cu" "B.Paste" "B.Mask")
			(roundrect_rratio 0.25)
			(net 4 "CSI1_D0_P")
			(pinfunction "R1.1")
			(pintype "passive")
		)
		(pad "2" smd roundrect
			(at -0.202 -0.298 90)
			(size 0.2 0.4)
			(layers "B.Cu" "B.Paste" "B.Mask")
			(roundrect_rratio 0.25)
			(net 2 "CSI1_D0_N")
			(pinfunction "R2.1")
			(pintype "passive")
		)
		(pad "3" smd roundrect
			(at 0.2 -0.298 90)
			(size 0.2 0.4)
			(layers "B.Cu" "B.Paste" "B.Mask")
			(roundrect_rratio 0.25)
			(net 12 "CSI1_D1_P")
			(pinfunction "R3.1")
			(pintype "passive")
		)
		(pad "4" smd roundrect
			(at 0.598 -0.298 90)
			(size 0.2 0.4)
			(layers "B.Cu" "B.Paste" "B.Mask")
			(roundrect_rratio 0.25)
			(net 10 "CSI1_D1_N")
			(pinfunction "R4.1")
			(pintype "passive")
		)
		(pad "5" smd roundrect
			(at 0.598 0.3 90)
			(size 0.2 0.4)
			(layers "B.Cu" "B.Paste" "B.Mask")
			(roundrect_rratio 0.25)
			(net 204 "/CSI/CSI1_0_D1_N")
			(pinfunction "R4.2")
			(pintype "passive")
		)
		(pad "6" smd roundrect
			(at 0.2 0.3 90)
			(size 0.2 0.4)
			(layers "B.Cu" "B.Paste" "B.Mask")
			(roundrect_rratio 0.25)
			(net 205 "/CSI/CSI1_0_D1_P")
			(pinfunction "R3.2")
			(pintype "passive")
		)
		(pad "7" smd roundrect
			(at -0.202 0.3 90)
			(size 0.2 0.4)
			(layers "B.Cu" "B.Paste" "B.Mask")
			(roundrect_rratio 0.25)
			(net 206 "/CSI/CSI1_0_D0_N")
			(pinfunction "R2.2")
			(pintype "passive")
		)
		(pad "8" smd roundrect
			(at -0.6 0.3 90)
			(size 0.2 0.4)
			(layers "B.Cu" "B.Paste" "B.Mask")
			(roundrect_rratio 0.25)
			(net 207 "/CSI/CSI1_0_D0_P")
			(pinfunction "R1.2")
			(pintype "passive")
		)
	)
	(footprint "antmicro-footprints:LED_0603_1608Metric_G"
		(layer "B.Cu")
		(at 47.1 126.95)
		(descr "LED SMD 0603 Green")
		(tags "LED SMD 0603 Green")
		(property "Reference" "D2"
			(at -7.4 1.27 0)
			(layer "B.SilkS")
			(effects
				(font
					(size 0.7 0.7)
					(thickness 0.15)
				)
				(justify right bottom mirror)
			)
		)
		(property "Value" "LED_G_0603_LTST-C190GKT"
			(at -0.001 -1.599 0)
			(layer "B.Fab")
			(effects
				(font
					(size 0.7 0.7)
					(thickness 0.15)
				)
				(justify right bottom mirror)
			)
		)
		(property "Footprint" "antmicro-footprints:LED_0603_1608Metric_G"
			(at 0 0 0)
			(layer "F.Fab")
			(hide yes)
			(effects
				(font
					(size 1.27 1.27)
					(thickness 0.15)
				)
			)
		)
		(property "Datasheet" "https://media.digikey.com/pdf/Data%20Sheets/Lite-On%20PDFs/LTST-C190GKT.pdf"
			(at 0 0 0)
			(layer "F.Fab")
			(hide yes)
			(effects
				(font
					(size 1.27 1.27)
					(thickness 0.15)
				)
			)
		)
		(property "Author" "Antmicro"
			(at 0 0 0)
			(layer "B.Fab")
			(hide yes)
			(effects
				(font
					(size 1 1)
					(thickness 0.15)
				)
				(justify mirror)
			)
		)
		(property "Color" "Green"
			(at 0 0 0)
			(layer "B.Fab")
			(hide yes)
			(effects
				(font
					(size 1 1)
					(thickness 0.15)
				)
				(justify mirror)
			)
		)
		(property "License" "Apache-2.0"
			(at 0 0 0)
			(layer "B.Fab")
			(hide yes)
			(effects
				(font
					(size 1 1)
					(thickness 0.15)
				)
				(justify mirror)
			)
		)
		(property "MPN" "LTST-C190GKT"
			(at 0 0 0)
			(layer "B.Fab")
			(hide yes)
			(effects
				(font
					(size 1 1)
					(thickness 0.15)
				)
				(justify mirror)
			)
		)
		(property "Manufacturer" "Lite-On"
			(at 0 0 0)
			(layer "B.Fab")
			(hide yes)
			(effects
				(font
					(size 1 1)
					(thickness 0.15)
				)
				(justify mirror)
			)
		)
		(sheetname "USB Debug, DP")
		(sheetfile "usb.kicad_sch")
		(attr smd)
		(fp_line
			(start -1.18 -0.321)
			(end -1.18 0.319)
			(stroke
				(width 0.15)
				(type solid)
			)
			(layer "B.SilkS")
		)
		(fp_line
			(start -0.24 -0.001008)
			(end -0.094672 -0.001008)
			(stroke
				(width 0.1)
				(type solid)
			)
			(layer "B.SilkS")
		)
		(fp_line
			(start -0.22 -0.35)
			(end 0.22 -0.35)
			(stroke
				(width 0.15)
				(type solid)
			)
			(layer "B.SilkS")
		)
		(fp_line
			(start -0.22 0.35)
			(end 0.22 0.35)
			(stroke
				(width 0.15)
				(type solid)
			)
			(layer "B.SilkS")
		)
		(fp_line
			(start -0.094672 -0.001008)
			(end 0.105328 -0.201008)
			(stroke
				(width 0.1)
				(type solid)
			)
			(layer "B.SilkS")
		)
		(fp_line
			(start -0.094672 0.198992)
			(end -0.094672 -0.201008)
			(stroke
				(width 0.1)
				(type solid)
			)
			(layer "B.SilkS")
		)
		(fp_line
			(start 0.105328 0.198992)
			(end -0.094672 -0.001008)
			(stroke
				(width 0.1)
				(type solid)
			)
			(layer "B.SilkS")
		)
		(fp_line
			(start 0.105328 0.198992)
			(end 0.105328 -0.201008)
			(stroke
				(width 0.1)
				(type solid)
			)
			(layer "B.SilkS")
		)
		(fp_line
			(start 0.24 -0.001)
			(end 0.105328 -0.001008)
			(stroke
				(width 0.1)
				(type solid)
			)
			(layer "B.SilkS")
		)
		(fp_rect
			(start 1.25 -0.65)
			(end -1.25 0.65)
			(stroke
				(width 0.05)
				(type solid)
			)
			(fill none)
			(layer "B.CrtYd")
		)
		(fp_line
			(start -0.597 0)
			(end -0.199 0)
			(stroke
				(width 0.15)
				(type solid)
			)
			(layer "B.Fab")
		)
		(fp_line
			(start -0.199 -0.1)
			(end -0.199 -0.2)
			(stroke
				(width 0.15)
				(type solid)
			)
			(layer "B.Fab")
		)
		(fp_line
			(start -0.199 -0.1)
			(end -0.199 0.202)
			(stroke
				(width 0.15)
				(type solid)
			)
			(layer "B.Fab")
		)
		(fp_line
			(start -0.101 0)
			(end 0.201 0.202)
			(stroke
				(width 0.15)
				(type solid)
			)
			(layer "B.Fab")
		)
		(fp_line
			(start 0.201 -0.2)
			(end -0.101 0)
			(stroke
				(width 0.15)
				(type solid)
			)
			(layer "B.Fab")
		)
		(fp_line
			(start 0.201 0)
			(end 0.201 -0.2)
			(stroke
				(width 0.15)
				(type solid)
			)
			(layer "B.Fab")
		)
		(fp_line
			(start 0.201 0)
			(end 0.599 0)
			(stroke
				(width 0.15)
				(type solid)
			)
			(layer "B.Fab")
		)
		(fp_line
			(start 0.201 0.202)
			(end 0.201 0)
			(stroke
				(width 0.15)
				(type solid)
			)
			(layer "B.Fab")
		)
		(fp_rect
			(start 0.848 -0.4)
			(end -0.85 0.402)
			(stroke
				(width 0.15)
				(type solid)
			)
			(fill none)
			(layer "B.Fab")
		)
		(fp_text user "Author: Antmicro"
			(at -1.4224 -4.799 0)
			(layer "B.Fab")
			(hide yes)
			(effects
				(font
					(size 0.7 0.7)
					(thickness 0.15)
				)
				(justify right bottom mirror)
			)
		)
		(fp_text user "${REFERENCE}"
			(at -1.4224 -5.999 0)
			(layer "B.Fab")
			(hide yes)
			(effects
				(font
					(size 0.7 0.7)
					(thickness 0.15)
				)
				(justify right bottom mirror)
			)
		)
		(fp_text user "License: Apache-2.0"
			(at -1.4224 -3.599 0)
			(layer "B.Fab")
			(hide yes)
			(effects
				(font
					(size 0.7 0.7)
					(thickness 0.15)
				)
				(justify right bottom mirror)
			)
		)
		(pad "1" smd roundrect
			(at -0.7 0 180)
			(size 0.8 1)
			(layers "B.Cu" "B.Paste" "B.Mask")
			(roundrect_rratio 0.2)
			(net 271 "/USB Debug, DP/FTDI_LED_TX")
			(pinfunction "C")
			(pintype "passive")
		)
		(pad "2" smd roundrect
			(at 0.7 0 180)
			(size 0.8 1)
			(layers "B.Cu" "B.Paste" "B.Mask")
			(roundrect_rratio 0.2)
			(net 142 "Net-(D2-A)")
			(pinfunction "A")
			(pintype "passive")
		)
	)
)
